(kicad_pcb
	(version 20241229)
	(generator "pcbnew")
	(generator_version "9.0")
	(general
		(thickness 1.294)
		(legacy_teardrops no)
	)
	(paper "A3")
	(title_block
		(title "Kintex 410T devboard")
		(date "2024-04-03")
		(rev "1.1.2")
		(comment 9 "footprints 443-447 of 975")
	)
	(layers
		(0 "F.Cu" mixed)
		(4 "In1.Cu" power)
		(6 "In2.Cu" power)
		(8 "In3.Cu" mixed)
		(10 "In4.Cu" power)
		(12 "In5.Cu" mixed)
		(14 "In6.Cu" power)
		(16 "In7.Cu" mixed)
		(18 "In8.Cu" power)
		(2 "B.Cu" mixed)
		(9 "F.Adhes" user "F.Adhesive")
		(11 "B.Adhes" user "B.Adhesive")
		(13 "F.Paste" user)
		(15 "B.Paste" user)
		(5 "F.SilkS" user "F.Silkscreen")
		(7 "B.SilkS" user "B.Silkscreen")
		(1 "F.Mask" user)
		(3 "B.Mask" user)
		(17 "Dwgs.User" user "User.Drawings")
		(19 "Cmts.User" user "User.Comments")
		(21 "Eco1.User" user "User.Eco1")
		(23 "Eco2.User" user "User.Eco2")
		(25 "Edge.Cuts" user)
		(27 "Margin" user)
		(31 "F.CrtYd" user "F.Courtyard")
		(29 "B.CrtYd" user "B.Courtyard")
		(35 "F.Fab" user)
		(33 "B.Fab" user)
	)
	(footprint "antmicro-footprints:QSOP-16_3.9x4.9mm_P0.635mm"
		(layer "F.Cu")
		(at 219.8 162.3 180)
		(descr "16-Lead Plastic Shrink Small Outline Narrow Body (QR)-.150\" Body [QSOP] (see Microchip Packaging Specification 00000049BS.pdf)")
		(tags "SSOP 0.635")
		(property "Reference" "U3"
			(at -1.97 2.93 180)
			(layer "F.SilkS")
			(effects
				(font
					(size 0.7 0.7)
					(thickness 0.15)
				)
				(justify left bottom)
			)
		)
		(property "Value" "MAX1617AMEE+T"
			(at -8.22 3.67 180)
			(layer "F.Fab")
			(effects
				(font
					(size 0.7 0.7)
					(thickness 0.15)
				)
				(justify left bottom)
			)
		)
		(property "Description" "Temperature sensor"
			(at 0 0 180)
			(layer "F.Fab")
			(hide yes)
			(effects
				(font
					(size 1.27 1.27)
					(thickness 0.15)
				)
			)
		)
		(property "Author" "Antmicro"
			(at 439.6 324.6 0)
			(layer "F.Fab")
			(hide yes)
			(effects
				(font
					(size 1 1)
					(thickness 0.15)
				)
			)
		)
		(property "License" "Apache-2.0"
			(at 439.6 324.6 0)
			(layer "F.Fab")
			(hide yes)
			(effects
				(font
					(size 1 1)
					(thickness 0.15)
				)
			)
		)
		(property "MPN" "MAX1617AMEE+T"
			(at 439.6 324.6 0)
			(layer "F.Fab")
			(hide yes)
			(effects
				(font
					(size 1 1)
					(thickness 0.15)
				)
			)
		)
		(property "Manufacturer" "Maxim Integrated Products"
			(at 439.6 324.6 0)
			(layer "F.Fab")
			(hide yes)
			(effects
				(font
					(size 1 1)
					(thickness 0.15)
				)
			)
		)
		(sheetname "FPGA Config")
		(sheetfile "fpga-config.kicad_sch")
		(attr smd)
		(fp_line
			(start -1.835 -2.73)
			(end 1.874 -2.73)
			(stroke
				(width 0.15)
				(type solid)
			)
			(layer "F.SilkS")
		)
		(fp_line
			(start -1.855 2.672)
			(end 1.854 2.672)
			(stroke
				(width 0.15)
				(type solid)
			)
			(layer "F.SilkS")
		)
		(fp_circle
			(center -2.657 -2.73)
			(end -2.606 -2.73)
			(stroke
				(width 0.15)
				(type solid)
			)
			(fill yes)
			(layer "F.SilkS")
		)
		(fp_rect
			(start -3.5 -2.952)
			(end 3.499 2.95)
			(stroke
				(width 0.05)
				(type solid)
			)
			(fill no)
			(layer "F.CrtYd")
		)
		(fp_line
			(start 1.949 2.45)
			(end -1.95 2.45)
			(stroke
				(width 0.15)
				(type solid)
			)
			(layer "F.Fab")
		)
		(fp_line
			(start 1.949 -2.452)
			(end 1.949 2.45)
			(stroke
				(width 0.15)
				(type solid)
			)
			(layer "F.Fab")
		)
		(fp_line
			(start -0.951 -2.452)
			(end 1.949 -2.452)
			(stroke
				(width 0.15)
				(type solid)
			)
			(layer "F.Fab")
		)
		(fp_line
			(start -1.95 2.45)
			(end -1.95 -1.45)
			(stroke
				(width 0.15)
				(type solid)
			)
			(layer "F.Fab")
		)
		(fp_line
			(start -1.95 -1.45)
			(end -0.951 -2.452)
			(stroke
				(width 0.15)
				(type solid)
			)
			(layer "F.Fab")
		)
		(pad "1" smd rect
			(at -2.656 -2.223 180)
			(size 1.6 0.41)
			(layers "F.Cu" "F.Mask" "F.Paste")
			(net 1058 "unconnected-(U3-NC-Pad1)")
			(pinfunction "NC")
			(pintype "no_connect")
		)
		(pad "2" smd rect
			(at -2.656 -1.589 180)
			(size 1.6 0.41)
			(layers "F.Cu" "F.Mask" "F.Paste")
			(net 24 "+3V3")
			(pinfunction "VCC")
			(pintype "power_in")
		)
		(pad "3" smd rect
			(at -2.656 -0.954 180)
			(size 1.6 0.41)
			(layers "F.Cu" "F.Mask" "F.Paste")
			(net 10 "/FPGA Config/FPGA_CFG_DXP")
			(pinfunction "DXP")
			(pintype "input")
		)
		(pad "4" smd rect
			(at -2.656 -0.318 180)
			(size 1.6 0.41)
			(layers "F.Cu" "F.Mask" "F.Paste")
			(net 9 "/FPGA Config/FPGA_CFG_DXN")
			(pinfunction "DXN")
			(pintype "input")
		)
		(pad "5" smd rect
			(at -2.656 0.315 180)
			(size 1.6 0.41)
			(layers "F.Cu" "F.Mask" "F.Paste")
			(net 1059 "unconnected-(U3-NC-Pad5)")
			(pinfunction "NC")
			(pintype "no_connect")
		)
		(pad "6" smd rect
			(at -2.656 0.951 180)
			(size 1.6 0.41)
			(layers "F.Cu" "F.Mask" "F.Paste")
			(net 1 "GND")
			(pinfunction "ADD1")
			(pintype "input")
		)
		(pad "7" smd rect
			(at -2.656 1.586 180)
			(size 1.6 0.41)
			(layers "F.Cu" "F.Mask" "F.Paste")
			(net 1 "GND")
			(pinfunction "GND")
			(pintype "power_in")
		)
		(pad "8" smd rect
			(at -2.656 2.221 180)
			(size 1.6 0.41)
			(layers "F.Cu" "F.Mask" "F.Paste")
			(net 1 "GND")
			(pinfunction "GND")
			(pintype "passive")
		)
		(pad "9" smd rect
			(at 2.652 2.221 180)
			(size 1.6 0.41)
			(layers "F.Cu" "F.Mask" "F.Paste")
			(net 1119 "unconnected-(U3-NC-Pad9)")
			(pinfunction "NC")
			(pintype "no_connect")
		)
		(pad "10" smd rect
			(at 2.652 1.586 180)
			(size 1.6 0.41)
			(layers "F.Cu" "F.Mask" "F.Paste")
			(net 1 "GND")
			(pinfunction "ADD0")
			(pintype "input")
		)
		(pad "11" smd rect
			(at 2.652 0.951 180)
			(size 1.6 0.41)
			(layers "F.Cu" "F.Mask" "F.Paste")
			(net 113 "/FPGA Config/TEMP_~{ALERT}")
			(pinfunction "~{ALERT}")
			(pintype "output")
		)
		(pad "12" smd rect
			(at 2.652 0.315 180)
			(size 1.6 0.41)
			(layers "F.Cu" "F.Mask" "F.Paste")
			(net 1336 "/I2C.SDA")
			(pinfunction "SMBDATA")
			(pintype "bidirectional")
		)
		(pad "13" smd rect
			(at 2.652 -0.318 180)
			(size 1.6 0.41)
			(layers "F.Cu" "F.Mask" "F.Paste")
			(net 1120 "unconnected-(U3-NC-Pad13)")
			(pinfunction "NC")
			(pintype "no_connect")
		)
		(pad "14" smd rect
			(at 2.652 -0.954 180)
			(size 1.6 0.41)
			(layers "F.Cu" "F.Mask" "F.Paste")
			(net 1338 "/I2C.SCL")
			(pinfunction "SMBCLK")
			(pintype "input")
		)
		(pad "15" smd rect
			(at 2.652 -1.589 180)
			(size 1.6 0.41)
			(layers "F.Cu" "F.Mask" "F.Paste")
			(net 345 "Net-(U3-STBY)")
			(pinfunction "STBY")
			(pintype "input")
		)
		(pad "16" smd rect
			(at 2.652 -2.223 180)
			(size 1.6 0.41)
			(layers "F.Cu" "F.Mask" "F.Paste")
			(net 1121 "unconnected-(U3-NC-Pad16)")
			(pinfunction "NC")
			(pintype "no_connect")
		)
	)
	(footprint "antmicro-footprints:C_0402_1005Metric"
		(layer "F.Cu")
		(at 254.445 134.935 180)
		(descr "Capacitor SMD 0402")
		(tags "capacitor SMD 0402")
		(property "Reference" "C232"
			(at 1.4 3.985 180)
			(layer "F.SilkS")
			(effects
				(font
					(size 0.7 0.7)
					(thickness 0.15)
				)
				(justify left bottom)
			)
		)
		(property "Value" "C_100n_0402"
			(at 0 1.169 180)
			(layer "F.Fab")
			(effects
				(font
					(size 0.7 0.7)
					(thickness 0.15)
				)
				(justify left bottom)
			)
		)
		(property "Description" "SMD Multilayer Ceramic Capacitor, 0.1 µF, 50 V, 0402 [1005 Metric], ± 10%, X5R, GRM Series"
			(at 0 0 180)
			(layer "F.Fab")
			(hide yes)
			(effects
				(font
					(size 1.27 1.27)
					(thickness 0.15)
				)
			)
		)
		(property "Author" "Antmicro"
			(at 508.89 269.87 0)
			(layer "F.Fab")
			(hide yes)
			(effects
				(font
					(size 1 1)
					(thickness 0.15)
				)
			)
		)
		(property "Dielectric" "X5R"
			(at 508.89 269.87 0)
			(layer "F.Fab")
			(hide yes)
			(effects
				(font
					(size 1 1)
					(thickness 0.15)
				)
			)
		)
		(property "License" "Apache-2.0"
			(at 508.89 269.87 0)
			(layer "F.Fab")
			(hide yes)
			(effects
				(font
					(size 1 1)
					(thickness 0.15)
				)
			)
		)
		(property "MPN" "GRM155R61H104KE14D"
			(at 508.89 269.87 0)
			(layer "F.Fab")
			(hide yes)
			(effects
				(font
					(size 1 1)
					(thickness 0.15)
				)
			)
		)
		(property "Manufacturer" "Murata"
			(at 508.89 269.87 0)
			(layer "F.Fab")
			(hide yes)
			(effects
				(font
					(size 1 1)
					(thickness 0.15)
				)
			)
		)
		(property "Val" "100n"
			(at 508.89 269.87 0)
			(layer "F.Fab")
			(hide yes)
			(effects
				(font
					(size 1 1)
					(thickness 0.15)
				)
			)
		)
		(property "Voltage" "50V"
			(at 508.89 269.87 0)
			(layer "F.Fab")
			(hide yes)
			(effects
				(font
					(size 1 1)
					(thickness 0.15)
				)
			)
		)
		(sheetname "USB PHY")
		(sheetfile "usb-phy.kicad_sch")
		(attr smd)
		(fp_rect
			(start -0.925 -0.47)
			(end 0.925 0.47)
			(stroke
				(width 0.05)
				(type default)
			)
			(fill no)
			(layer "F.CrtYd")
		)
		(fp_line
			(start 0.504 0.248)
			(end -0.494 0.248)
			(stroke
				(width 0.15)
				(type solid)
			)
			(layer "F.Fab")
		)
		(fp_line
			(start 0.504 -0.25)
			(end 0.504 0.248)
			(stroke
				(width 0.15)
				(type solid)
			)
			(layer "F.Fab")
		)
		(fp_line
			(start -0.494 0.248)
			(end -0.494 -0.25)
			(stroke
				(width 0.15)
				(type solid)
			)
			(layer "F.Fab")
		)
		(fp_line
			(start -0.494 -0.25)
			(end 0.504 -0.25)
			(stroke
				(width 0.15)
				(type solid)
			)
			(layer "F.Fab")
		)
		(pad "1" smd roundrect
			(at -0.48 0 180)
			(size 0.59 0.64)
			(layers "F.Cu" "F.Mask" "F.Paste")
			(roundrect_rratio 0.25)
			(net 1 "GND")
			(pintype "passive")
		)
		(pad "2" smd roundrect
			(at 0.48 0 180)
			(size 0.59 0.64)
			(layers "F.Cu" "F.Mask" "F.Paste")
			(roundrect_rratio 0.25)
			(net 711 "/USB PHY/FTDI_VPLL")
			(pintype "passive")
		)
	)
	(footprint "antmicro-footprints:R_Array_4x0201_Panasonic_EXB18V"
		(layer "F.Cu")
		(at 253.9 144.302)
		(property "Reference" "R282"
			(at -19.35 -38.052 0)
			(layer "F.SilkS")
			(effects
				(font
					(size 0.7 0.7)
					(thickness 0.15)
				)
				(justify right bottom)
			)
		)
		(property "Value" "R_4x33R_0201_array"
			(at -1.1 1.8 0)
			(layer "F.Fab")
			(effects
				(font
					(size 0.7 0.7)
					(thickness 0.15)
				)
				(justify left bottom)
			)
		)
		(property "Description" "Fixed Network Resistor, 33 ohm, Isolated, 4 Resistors, 0502 [1406 Metric], Flat, ± 5%"
			(at 0 0 0)
			(layer "F.Fab")
			(hide yes)
			(effects
				(font
					(size 1.27 1.27)
					(thickness 0.15)
				)
			)
		)
		(property "Author" "Antmicro"
			(at 0 0 0)
			(layer "F.Fab")
			(hide yes)
			(effects
				(font
					(size 1 1)
					(thickness 0.15)
				)
			)
		)
		(property "License" "Apache-2.0"
			(at 0 0 0)
			(layer "F.Fab")
			(hide yes)
			(effects
				(font
					(size 1 1)
					(thickness 0.15)
				)
			)
		)
		(property "MPN" "EXB-18V330JX"
			(at 0 0 0)
			(layer "F.Fab")
			(hide yes)
			(effects
				(font
					(size 1 1)
					(thickness 0.15)
				)
			)
		)
		(property "Manufacturer" "Panasonic"
			(at 0 0 0)
			(layer "F.Fab")
			(hide yes)
			(effects
				(font
					(size 1 1)
					(thickness 0.15)
				)
			)
		)
		(property "Val" "R_4x33R_0201"
			(at 0 0 0)
			(layer "F.Fab")
			(hide yes)
			(effects
				(font
					(size 1 1)
					(thickness 0.15)
				)
			)
		)
		(sheetname "Supervisior MCU")
		(sheetfile "supervisor-mcu.kicad_sch")
		(attr smd)
		(fp_line
			(start -0.8 -0.45)
			(end -0.8 0.45)
			(stroke
				(width 0.12)
				(type solid)
			)
			(layer "F.SilkS")
		)
		(fp_line
			(start 0.8 -0.45)
			(end 0.8 0.45)
			(stroke
				(width 0.12)
				(type solid)
			)
			(layer "F.SilkS")
		)
		(fp_rect
			(start -0.898 -0.66)
			(end 0.898 0.65)
			(stroke
				(width 0.05)
				(type solid)
			)
			(fill no)
			(layer "F.CrtYd")
		)
		(pad "1" smd roundrect
			(at -0.6 0.298)
			(size 0.2 0.4)
			(layers "F.Cu" "F.Mask" "F.Paste")
			(roundrect_rratio 0.25)
			(net 1093 "/Supervisior MCU/USB_ALE")
			(pinfunction "R1.1")
			(pintype "passive")
		)
		(pad "2" smd roundrect
			(at -0.202 0.298)
			(size 0.2 0.4)
			(layers "F.Cu" "F.Mask" "F.Paste")
			(roundrect_rratio 0.25)
			(net 1086 "/Supervisior MCU/PGOOD_3V3")
			(pinfunction "R2.1")
			(pintype "passive")
		)
		(pad "3" smd roundrect
			(at 0.2 0.298)
			(size 0.2 0.4)
			(layers "F.Cu" "F.Mask" "F.Paste")
			(roundrect_rratio 0.25)
			(net 1070 "/Supervisior MCU/USB_A9")
			(pinfunction "R3.1")
			(pintype "passive")
		)
		(pad "4" smd roundrect
			(at 0.598 0.298)
			(size 0.2 0.4)
			(layers "F.Cu" "F.Mask" "F.Paste")
			(roundrect_rratio 0.25)
			(net 1094 "/Supervisior MCU/USB_RD")
			(pinfunction "R4.1")
			(pintype "passive")
		)
		(pad "5" smd roundrect
			(at 0.598 -0.3)
			(size 0.2 0.4)
			(layers "F.Cu" "F.Mask" "F.Paste")
			(roundrect_rratio 0.25)
			(net 1390 "/SUP_MCU.RD")
			(pinfunction "R4.2")
			(pintype "passive")
		)
		(pad "6" smd roundrect
			(at 0.2 -0.3)
			(size 0.2 0.4)
			(layers "F.Cu" "F.Mask" "F.Paste")
			(roundrect_rratio 0.25)
			(net 1391 "/SUP_MCU.A9")
			(pinfunction "R3.2")
			(pintype "passive")
		)
		(pad "7" smd roundrect
			(at -0.202 -0.3)
			(size 0.2 0.4)
			(layers "F.Cu" "F.Mask" "F.Paste")
			(roundrect_rratio 0.25)
			(net 1387 "/SUP_MCU.PG_3V3")
			(pinfunction "R2.2")
			(pintype "passive")
		)
		(pad "8" smd roundrect
			(at -0.6 -0.3)
			(size 0.2 0.4)
			(layers "F.Cu" "F.Mask" "F.Paste")
			(roundrect_rratio 0.25)
			(net 1392 "/SUP_MCU.ALE")
			(pinfunction "R1.2")
			(pintype "passive")
		)
	)
	(footprint "antmicro-footprints:NetTie-2_SMD_Pad0.127mm"
		(layer "F.Cu")
		(at 197.760197 131.239803 -135)
		(descr "Net tie, 2 pin, 0.127mm  SMD pads")
		(tags "net tie")
		(property "Reference" "NT24"
			(at -0.128 -1.345 225)
			(layer "F.SilkS")
			(hide yes)
			(effects
				(font
					(size 0.7 0.7)
					(thickness 0.15)
				)
				(justify left bottom)
			)
		)
		(property "Value" "Net-Tie_2"
			(at 0 1.199 225)
			(layer "F.Fab")
			(effects
				(font
					(size 0.7 0.7)
					(thickness 0.15)
				)
				(justify left bottom)
			)
		)
		(property "Description" "Net tie, 2 pins"
			(at 0 0 225)
			(layer "F.Fab")
			(hide yes)
			(effects
				(font
					(size 1.27 1.27)
					(thickness 0.15)
				)
			)
		)
		(property "Author" "Antmicro"
			(at 244.797219 363.877934 0)
			(layer "F.Fab")
			(hide yes)
			(effects
				(font
					(size 1 1)
					(thickness 0.15)
				)
			)
		)
		(property "License" "Apache-2.0"
			(at 244.797219 363.877934 0)
			(layer "F.Fab")
			(hide yes)
			(effects
				(font
					(size 1 1)
					(thickness 0.15)
				)
			)
		)
		(property "MPN" ""
			(at 244.797219 363.877934 0)
			(layer "F.Fab")
			(hide yes)
			(effects
				(font
					(size 1 1)
					(thickness 0.15)
				)
			)
		)
		(property "Manufacturer" ""
			(at 244.797219 363.877934 0)
			(layer "F.Fab")
			(hide yes)
			(effects
				(font
					(size 1 1)
					(thickness 0.15)
				)
			)
		)
		(sheetname "FPGA Config")
		(sheetfile "fpga-config.kicad_sch")
		(attr exclude_from_pos_files)
		(net_tie_pad_groups "1, 2")
		(fp_poly
			(pts
				(xy -0.0635 -0.0635) (xy 0.0625 -0.0635) (xy 0.0625 0.0635) (xy -0.0635 0.0635)
			)
			(stroke
				(width 0)
				(type solid)
			)
			(fill yes)
			(layer "F.Cu")
		)
		(pad "1" smd roundrect
			(at -0.127001 0 45)
			(size 0.127 0.127)
			(layers "F.Cu")
			(roundrect_rratio 0.5)
			(chamfer_ratio 0)
			(chamfer top_left bottom_left)
			(net 870 "VREFN")
			(pinfunction "1")
			(pintype "passive")
		)
		(pad "2" smd roundrect
			(at 0.125999 0 225)
			(size 0.127 0.127)
			(layers "F.Cu")
			(roundrect_rratio 0.5)
			(chamfer_ratio 0)
			(chamfer top_left bottom_left)
			(net 1 "GND")
			(pinfunction "2")
			(pintype "passive")
		)
	)
	(footprint "antmicro-footprints:R_0402_1005Metric"
		(layer "F.Cu")
		(at 190.515001 148.785001)
		(descr "Resistor SMD 0402")
		(tags "resistor SMD 0402")
		(property "Reference" "R334"
			(at -0.965001 -0.485001 0)
			(layer "F.SilkS")
			(effects
				(font
					(size 0.7 0.7)
					(thickness 0.15)
				)
				(justify left bottom)
			)
		)
		(property "Value" "R_100R_0402"
			(at 0 1.4 0)
			(layer "F.Fab")
			(effects
				(font
					(size 0.7 0.7)
					(thickness 0.15)
				)
				(justify left bottom)
			)
		)
		(property "Description" "SMD Chip Resistor, 100 ohm, ± 1%, 62.5 mW, 0402 [1005 Metric], Thick Film, General Purpose"
			(at 0 0 0)
			(layer "F.Fab")
			(hide yes)
			(effects
				(font
					(size 1.27 1.27)
					(thickness 0.15)
				)
			)
		)
		(property "Author" "Antmicro"
			(at 0 0 0)
			(layer "F.Fab")
			(hide yes)
			(effects
				(font
					(size 1 1)
					(thickness 0.15)
				)
			)
		)
		(property "License" "Apache-2.0"
			(at 0 0 0)
			(layer "F.Fab")
			(hide yes)
			(effects
				(font
					(size 1 1)
					(thickness 0.15)
				)
			)
		)
		(property "MPN" "CR0402-FX-1000GLF"
			(at 0 0 0)
			(layer "F.Fab")
			(hide yes)
			(effects
				(font
					(size 1 1)
					(thickness 0.15)
				)
			)
		)
		(property "Manufacturer" "Bourns"
			(at 0 0 0)
			(layer "F.Fab")
			(hide yes)
			(effects
				(font
					(size 1 1)
					(thickness 0.15)
				)
			)
		)
		(property "Tolerance" "1%"
			(at 0 0 0)
			(layer "F.Fab")
			(hide yes)
			(effects
				(font
					(size 1 1)
					(thickness 0.15)
				)
			)
		)
		(property "Val" "100R"
			(at 0 0 0)
			(layer "F.Fab")
			(hide yes)
			(effects
				(font
					(size 1 1)
					(thickness 0.15)
				)
			)
		)
		(sheetname "Clocks")
		(sheetfile "clocks.kicad_sch")
		(attr smd)
		(fp_rect
			(start -0.925 -0.47)
			(end 0.925 0.47)
			(stroke
				(width 0.05)
				(type default)
			)
			(fill no)
			(layer "F.CrtYd")
		)
		(fp_rect
			(start -0.5 -0.25)
			(end 0.5 0.25)
			(stroke
				(width 0.15)
				(type solid)
			)
			(fill no)
			(layer "F.Fab")
		)
		(pad "1" smd roundrect
			(at -0.48 0)
			(size 0.59 0.64)
			(layers "F.Cu" "F.Mask" "F.Paste")
			(roundrect_rratio 0.25)
			(net 623 "/Clocks/SYS.CLK_N")
			(pintype "passive")
		)
		(pad "2" smd roundrect
			(at 0.48 0)
			(size 0.59 0.64)
			(layers "F.Cu" "F.Mask" "F.Paste")
			(roundrect_rratio 0.25)
			(net 624 "/Clocks/SYS.CLK_P")
			(pintype "passive")
		)
	)
)
